(kicad_pcb
	(version 20221018)
	(generator pcbnew)
	(general
    (thickness 1.7403)
  )
	(paper "A4")
	(title_block
    (title "Data Center RDIMM DDR4 Tester")
    (date "2024-09-30")
    (rev "1.2.4")
		(comment 9 "footprints 365-372 of 690")
	)
	(layers
    (0 "F.Cu" signal)
    (1 "In1.Cu" power)
    (2 "In2.Cu" signal)
    (3 "In3.Cu" power)
    (4 "In4.Cu" power)
    (5 "In5.Cu" signal)
    (6 "In6.Cu" power)
    (7 "In7.Cu" signal)
    (8 "In8.Cu" power)
    (9 "In9.Cu" signal)
    (10 "In10.Cu" power)
    (31 "B.Cu" signal)
    (32 "B.Adhes" user "B.Adhesive")
    (33 "F.Adhes" user "F.Adhesive")
    (34 "B.Paste" user)
    (35 "F.Paste" user)
    (36 "B.SilkS" user "B.Silkscreen")
    (37 "F.SilkS" user "F.Silkscreen")
    (38 "B.Mask" user)
    (39 "F.Mask" user)
    (40 "Dwgs.User" user "User.Drawings")
    (41 "Cmts.User" user "User.Comments")
    (42 "Eco1.User" user "User.Eco1")
    (43 "Eco2.User" user "User.Eco2")
    (44 "Edge.Cuts" user)
    (45 "Margin" user)
    (46 "B.CrtYd" user "B.Courtyard")
    (47 "F.CrtYd" user "F.Courtyard")
    (48 "B.Fab" user)
    (49 "F.Fab" user)
  )
	(footprint "data-center-rdimm-ddr4-tester-footprints:C_0402_1005Metric" (layer "F.Cu")
    (at 256.62 99.5)
    (descr "Capacitor SMD 0402")
    (tags "capacitor SMD 0402")
    (property "Author" "Antmicro")
    (property "Dielectric" "X5R")
    (property "License" "Apache-2.0")
    (property "MPN" "GRM155R61H104KE14D")
    (property "Manufacturer" "Murata")
    (property "Sheetfile" "pcie.kicad_sch")
    (property "Sheetname" "FPGA banks 115-116")
    (property "Val" "100n")
    (property "Voltage" "50V")
    (property "ki_description" " ")
    (attr smd)
    (fp_text reference "C198" (at -0.65 2.28) (layer "F.SilkS")
        (effects (font (size 0.7 0.7) (thickness 0.15)) (justify left bottom))
    )
    (fp_text value "C_100n_0402" (at 0 1.4) (layer "F.Fab") hide
        (effects (font (size 0.7 0.7) (thickness 0.15)) (justify left bottom))
    )
    (fp_text user "License: Apache-2.0" (at -0.932 5.17) (layer "F.Fab") hide
        (effects (font (size 0.7 0.7) (thickness 0.15)) (justify left bottom))
    )
    (fp_text user "Author: Antmicro" (at -0.932 4.17) (layer "F.Fab") hide
        (effects (font (size 0.7 0.7) (thickness 0.15)) (justify left bottom))
    )
    (fp_text user "${REFERENCE}" (at -0.932 3.168) (layer "F.Fab") hide
        (effects (font (size 0.7 0.7) (thickness 0.15)) (justify left bottom))
    )
    (fp_rect (start -0.94 -0.47) (end 0.94 0.47)
      (stroke (width 0.05) (type solid)) (fill none) (layer "F.CrtYd"))
    (fp_rect (start -0.499 -0.249) (end 0.499 0.249)
      (stroke (width 0.15) (type solid)) (fill none) (layer "F.Fab"))
    (pad "1" smd roundrect (at -0.484 0) (size 0.59 0.64) (layers "F.Cu" "F.Paste" "F.Mask") (roundrect_rratio 0.25)
      (net 892 "GTR_REFCLK1_C_N") (pintype "passive"))
    (pad "2" smd roundrect (at 0.484 0) (size 0.59 0.64) (layers "F.Cu" "F.Paste" "F.Mask") (roundrect_rratio 0.25)
      (net 884 "/FPGA banks 115-116/GTR_REFCLK1_N") (pintype "passive"))
  )
	(footprint "data-center-rdimm-ddr4-tester-footprints:NetTie-2_SMD_Pad0.127mm" (layer "F.Cu")
    (at 131.6 100.367 -90)
    (descr "Net tie, 2 pin, 0.127mm  SMD pads")
    (tags "net tie")
    (property "Author" "Antmicro")
    (property "License" "Apache-2.0")
    (property "MPN" "")
    (property "Manufacturer" "")
    (property "Sheetfile" "supply.kicad_sch")
    (property "Sheetname" "Supply")
    (property "ki_description" "Net tie, 2 pins")
    (property "ki_keywords" "net tie short")
    (attr through_hole exclude_from_pos_files)
    (net_tie_pad_groups "1, 2")
    (fp_text reference "NT7" (at -0.128 -1.345 -90) (layer "F.SilkS") hide
        (effects (font (size 0.7 0.7) (thickness 0.15)) (justify left bottom))
    )
    (fp_text value "Net-Tie_2" (at 0 1.199 -90) (layer "F.Fab") hide
        (effects (font (size 0.7 0.7) (thickness 0.15)) (justify left bottom))
    )
    (fp_text user "Author: Antmicro" (at -0.128 4.4 -90) (layer "F.Fab") hide
        (effects (font (size 0.7 0.7) (thickness 0.15)) (justify left bottom))
    )
    (fp_text user "${REFERENCE}" (at -0.128 3.2 -90) (layer "F.Fab") hide
        (effects (font (size 0.7 0.7) (thickness 0.15)) (justify left bottom))
    )
    (fp_text user "License: Apache-2.0" (at -0.128 5.6 -90) (layer "F.Fab") hide
        (effects (font (size 0.7 0.7) (thickness 0.15)) (justify left bottom))
    )
    (fp_poly
      (pts
        (xy -0.0635 -0.0635)
        (xy 0.0625 -0.0635)
        (xy 0.0625 0.0635)
        (xy -0.0635 0.0635)
      )

      (stroke (width 0) (type solid)) (fill solid) (layer "F.Cu"))
    (pad "1" smd roundrect (at -0.127 0 90) (size 0.127 0.127) (layers "F.Cu") (roundrect_rratio 0.5)
      (chamfer_ratio 0) (chamfer top_left bottom_left)
      (net 838 "/Supply/5V0_SEN_+") (pinfunction "1") (pintype "passive"))
    (pad "2" smd roundrect (at 0.126 0 270) (size 0.127 0.127) (layers "F.Cu") (roundrect_rratio 0.5)
      (chamfer_ratio 0) (chamfer top_left bottom_left)
      (net 104 "VCC5V0") (pinfunction "2") (pintype "passive"))
  )
	(footprint "data-center-rdimm-ddr4-tester-footprints:R_0402_1005Metric" (layer "F.Cu")
    (at 254.7 100.5)
    (descr "Resistor SMD 0402")
    (tags "resistor SMD 0402")
    (property "Author" "Antmicro")
    (property "License" "Apache-2.0")
    (property "MPN" "CR0402-FX-33R0GLF")
    (property "Manufacturer" "Bourns")
    (property "Sheetfile" "fmc_hpc.kicad_sch")
    (property "Sheetname" "FMC HPC")
    (property "Tolerance" "1%")
    (property "Val" "33R")
    (property "ki_description" "33R resistor in 0402 package with 1% tolerance")
    (attr smd)
    (fp_text reference "R148" (at -1.74 2.35) (layer "F.SilkS")
        (effects (font (size 0.7 0.7) (thickness 0.15)) (justify left bottom))
    )
    (fp_text value "R_33R_0402" (at 0 1.4) (layer "F.Fab") hide
        (effects (font (size 0.7 0.7) (thickness 0.15)) (justify left bottom))
    )
    (fp_text user "Author: Antmicro" (at -0.95 4.169) (layer "F.Fab") hide
        (effects (font (size 0.7 0.7) (thickness 0.15)) (justify left bottom))
    )
    (fp_text user "${REFERENCE}" (at -0.95 3.168) (layer "F.Fab") hide
        (effects (font (size 0.7 0.7) (thickness 0.15)) (justify left bottom))
    )
    (fp_text user "License: Apache-2.0" (at -0.95 5.169) (layer "F.Fab") hide
        (effects (font (size 0.7 0.7) (thickness 0.15)) (justify left bottom))
    )
    (fp_rect (start -0.93 -0.47) (end 0.93 0.47)
      (stroke (width 0.05) (type solid)) (fill none) (layer "F.CrtYd"))
    (fp_rect (start -0.5 -0.25) (end 0.5 0.25)
      (stroke (width 0.15) (type solid)) (fill none) (layer "F.Fab"))
    (pad "1" smd roundrect (at -0.485 0) (size 0.59 0.64) (layers "F.Cu" "F.Paste" "F.Mask") (roundrect_rratio 0.25)
      (net 897 "/FMC HPC/GTR_REFCLK1_R_P") (pintype "passive"))
    (pad "2" smd roundrect (at 0.485 0) (size 0.59 0.64) (layers "F.Cu" "F.Paste" "F.Mask") (roundrect_rratio 0.25)
      (net 891 "GTR_REFCLK1_C_P") (pintype "passive"))
  )
	(footprint "data-center-rdimm-ddr4-tester-footprints:R_1206_3216Metric" (layer "F.Cu")
    (at 143.9 83.7)
    (property "Author" "Antmicro")
    (property "License" "Apache-2.0")
    (property "MPN" "RL1206FR-7W0R01L")
    (property "Manufacturer" "Yaego")
    (property "Sheetfile" "supply.kicad_sch")
    (property "Sheetname" "Supply")
    (property "Tolerance" "1%")
    (property "Val" "0R01")
    (property "ki_description" "0R01 resistor in 1206 package with unspecified tolerance")
    (attr smd)
    (fp_text reference "R204" (at -0.75 1.9) (layer "F.SilkS")
        (effects (font (size 0.7 0.7) (thickness 0.15)) (justify left bottom))
    )
    (fp_text value "R_0R01_1206" (at 0 2) (layer "F.Fab") hide
        (effects (font (size 0.7 0.7) (thickness 0.15)) (justify left bottom))
    )
    (fp_text user "License: Apache-2.0" (at -2.401 6.3) (layer "F.Fab") hide
        (effects (font (size 0.7 0.7) (thickness 0.15)) (justify left bottom))
    )
    (fp_text user "Author: Antmicro" (at -2.401 4.899) (layer "F.Fab") hide
        (effects (font (size 0.7 0.7) (thickness 0.15)) (justify left bottom))
    )
    (fp_text user "${REFERENCE}" (at -2.401 3.5) (layer "F.Fab") hide
        (effects (font (size 0.7 0.7) (thickness 0.15)) (justify left bottom))
    )
    (fp_line (start 0 -0.902) (end -0.5 -0.902)
      (stroke (width 0.15) (type solid)) (layer "F.SilkS"))
    (fp_line (start 0 -0.902) (end 0.498 -0.902)
      (stroke (width 0.15) (type solid)) (layer "F.SilkS"))
    (fp_line (start 0 0.9) (end -0.5 0.9)
      (stroke (width 0.15) (type solid)) (layer "F.SilkS"))
    (fp_line (start 0 0.9) (end 0.498 0.9)
      (stroke (width 0.15) (type solid)) (layer "F.SilkS"))
    (fp_rect (start -2.25 -1.05) (end 2.25 1.05)
      (stroke (width 0.05) (type solid)) (fill none) (layer "F.CrtYd"))
    (fp_line (start -1.601 -0.802) (end -1.601 0.8)
      (stroke (width 0.15) (type solid)) (layer "F.Fab"))
    (fp_line (start -1.601 -0.802) (end 1.6 -0.802)
      (stroke (width 0.15) (type solid)) (layer "F.Fab"))
    (fp_line (start -1.601 0.8) (end 1.6 0.8)
      (stroke (width 0.15) (type solid)) (layer "F.Fab"))
    (fp_line (start 1.6 -0.802) (end 1.6 0.8)
      (stroke (width 0.15) (type solid)) (layer "F.Fab"))
    (pad "1" smd roundrect (at -1.5 0) (size 1.2 1.8) (layers "F.Cu" "F.Paste" "F.Mask") (roundrect_rratio 0.15)
      (net 300 "VCC1V0") (pintype "passive"))
    (pad "2" smd roundrect (at 1.499 0) (size 1.2 1.8) (layers "F.Cu" "F.Paste" "F.Mask") (roundrect_rratio 0.15)
      (net 147 "1V0_SYS") (pintype "passive"))
  )
	(footprint "data-center-rdimm-ddr4-tester-footprints:R_0201" (layer "F.Cu")
    (at 154.54 104.29 -90)
    (descr "Resistor SMD 0201")
    (tags "resistor SMD 0201")
    (property "Author" "Antmicro")
    (property "License" "Apache-2.0")
    (property "MPN" "CR0201-FX-0R00GLF")
    (property "Manufacturer" "Bourns")
    (property "Sheetfile" "ethernet.kicad_sch")
    (property "Sheetname" "Ethernet")
    (property "Tolerance" "1%")
    (property "Val" "0R")
    (property "ki_description" "0R resistor in 0201 package with 1% tolerance")
    (attr smd)
    (fp_text reference "R97" (at -0.62 -0.24 -90) (layer "F.SilkS")
        (effects (font (size 0.7 0.7) (thickness 0.15)) (justify left bottom))
    )
    (fp_text value "R_0R_0201" (at 0 1.25 -90) (layer "F.Fab") hide
        (effects (font (size 0.7 0.7) (thickness 0.15)) (justify left bottom))
    )
    (fp_text user "Author: Antmicro" (at -0.71 5.25 -90) (layer "F.Fab") hide
        (effects (font (size 0.7 0.7) (thickness 0.15)) (justify left bottom))
    )
    (fp_text user "License: Apache-2.0" (at -0.71 4.25 -90) (layer "F.Fab") hide
        (effects (font (size 0.7 0.7) (thickness 0.15)) (justify left bottom))
    )
    (fp_text user "${REFERENCE}" (at -0.71 3.25 -90) (layer "F.Fab") hide
        (effects (font (size 0.7 0.7) (thickness 0.15)) (justify left bottom))
    )
    (fp_rect (start -0.71 -0.36) (end 0.71 0.36)
      (stroke (width 0.05) (type solid)) (fill none) (layer "F.CrtYd"))
    (fp_rect (start -0.3 -0.15) (end 0.298 0.148)
      (stroke (width 0.15) (type solid)) (fill none) (layer "F.Fab"))
    (pad "" smd roundrect (at -0.346 0 270) (size 0.318 0.36) (layers "F.Paste") (roundrect_rratio 0.25))
    (pad "" smd roundrect (at 0.344 0 270) (size 0.318 0.36) (layers "F.Paste") (roundrect_rratio 0.25))
    (pad "1" smd roundrect (at -0.32 0 270) (size 0.46 0.4) (layers "F.Cu" "F.Mask") (roundrect_rratio 0.25)
      (net 170 "/Ethernet/ETH1_P") (pintype "passive"))
    (pad "2" smd roundrect (at 0.32 0 270) (size 0.46 0.4) (layers "F.Cu" "F.Mask") (roundrect_rratio 0.25)
      (net 824 "/Ethernet/ETH1_BP_P") (pintype "passive"))
  )
	(footprint "data-center-rdimm-ddr4-tester-footprints:PROBE_PAD_1206" (layer "F.Cu")
    (at 257.2 66.8 90)
    (property "Author" "Antmicro")
    (property "License" "Apache-2.0")
    (property "MPN" "RCW-0C")
    (property "Manufacturer" "TE Connectivity")
    (property "Sheetfile" "supply.kicad_sch")
    (property "Sheetname" "Supply")
    (property "ki_description" "SMD Circuit Probe Pad 1206")
    (attr smd)
    (fp_text reference "GND2" (at -1.5 -1.11 90) (layer "F.SilkS")
        (effects (font (size 0.7 0.7) (thickness 0.15)) (justify left bottom))
    )
    (fp_text value "TestPoint_Probe_1206_RCW-0C" (at 0 2.112 90) (layer "F.Fab") hide
        (effects (font (size 0.7 0.7) (thickness 0.15)) (justify left bottom))
    )
    (fp_text user "License: Apache-2.0" (at -1.95 6.512 90) (layer "F.Fab") hide
        (effects (font (size 0.7 0.7) (thickness 0.15)) (justify left bottom))
    )
    (fp_text user "${REFERENCE}" (at -1.95 4.112 90) (layer "F.Fab") hide
        (effects (font (size 0.7 0.7) (thickness 0.15)) (justify left bottom))
    )
    (fp_text user "Author: Antmicro" (at -1.95 5.312 90) (layer "F.Fab") hide
        (effects (font (size 0.7 0.7) (thickness 0.15)) (justify left bottom))
    )
    (fp_line (start -1.78 -0.92) (end -1.78 -0.419)
      (stroke (width 0.15) (type solid)) (layer "F.SilkS"))
    (fp_line (start -1.78 -0.92) (end -1.28 -0.92)
      (stroke (width 0.15) (type solid)) (layer "F.SilkS"))
    (fp_line (start -1.78 0.541) (end -1.78 1.04)
      (stroke (width 0.15) (type solid)) (layer "F.SilkS"))
    (fp_line (start -1.78 1.04) (end -1.28 1.04)
      (stroke (width 0.15) (type solid)) (layer "F.SilkS"))
    (fp_line (start 1.779 1.042) (end 1.28 1.042)
      (stroke (width 0.15) (type solid)) (layer "F.SilkS"))
    (fp_line (start 1.779 1.042) (end 1.779 0.542)
      (stroke (width 0.15) (type solid)) (layer "F.SilkS"))
    (fp_line (start 1.78 -0.92) (end 1.28 -0.92)
      (stroke (width 0.15) (type solid)) (layer "F.SilkS"))
    (fp_line (start 1.78 -0.92) (end 1.78 -0.419)
      (stroke (width 0.15) (type solid)) (layer "F.SilkS"))
    (fp_line (start -1.95 -1.08) (end -1.95 1.18)
      (stroke (width 0.05) (type solid)) (layer "F.CrtYd"))
    (fp_line (start 1.93 -1.08) (end -1.95 -1.08)
      (stroke (width 0.05) (type solid)) (layer "F.CrtYd"))
    (fp_line (start 1.93 -1.08) (end 1.93 1.18)
      (stroke (width 0.05) (type solid)) (layer "F.CrtYd"))
    (fp_line (start 1.93 1.18) (end -1.95 1.18)
      (stroke (width 0.05) (type solid)) (layer "F.CrtYd"))
    (fp_line (start -1.601 0.861) (end -1.601 -0.738)
      (stroke (width 0.15) (type solid)) (layer "F.Fab"))
    (fp_line (start 1.6 -0.738) (end -1.601 -0.738)
      (stroke (width 0.15) (type solid)) (layer "F.Fab"))
    (fp_line (start 1.6 0.861) (end -1.601 0.861)
      (stroke (width 0.15) (type solid)) (layer "F.Fab"))
    (fp_line (start 1.6 0.861) (end 1.6 -0.738)
      (stroke (width 0.15) (type solid)) (layer "F.Fab"))
    (pad "1" smd rect (at 0 0.061 90) (size 3.4 1.8) (layers "F.Cu" "F.Paste" "F.Mask")
      (net 9 "GND") (pinfunction "1") (pintype "passive"))
  )
	(footprint "data-center-rdimm-ddr4-tester-footprints:CONV_PDQE30-Q48-S5-D" (layer "F.Cu")
    (at 177.09 133.16 90)
    (property "Author" "Antmicro")
    (property "License" "Apache-2.0")
    (property "MPN" "PDQE30-Q48-S12-D")
    (property "Manufacturer" "CUI Inc")
    (property "Sheetfile" "ethernet.kicad_sch")
    (property "Sheetname" "Ethernet")
    (property "ki_description" "DC-DC CONVERTER, 48VDC input, 12VDC nom isolated output w/ trim option, 30W, 270kHz PWM mode")
    (property "ki_keywords" "dc converter step down 12v 48v isolated 30W poe")
    (attr through_hole)
    (fp_text reference "PS1" (at 23.21 20.76 180) (layer "F.SilkS")
        (effects (font (size 0.7 0.7) (thickness 0.15)) (justify left bottom))
    )
    (fp_text value "PDQE30-Q48-S12-D" (at 10.32 24.312 90) (layer "F.Fab")
        (effects (font (size 0.7 0.7) (thickness 0.15)) (justify left bottom))
    )
    (fp_text user "License: Apache-2.0" (at -3.912 27.51 90) (layer "F.Fab") hide
        (effects (font (size 0.7 0.7) (thickness 0.15)) (justify left bottom))
    )
    (fp_text user "${REFERENCE}" (at -3.912 28.711 90) (layer "F.Fab") hide
        (effects (font (size 0.7 0.7) (thickness 0.15)) (justify left bottom))
    )
    (fp_text user "Author: Antmicro" (at -3.912 26.312 90) (layer "F.Fab") hide
        (effects (font (size 0.7 0.7) (thickness 0.15)) (justify left bottom))
    )
    (fp_line (start -2.54 -2.54) (end 22.859 -2.54)
      (stroke (width 0.15) (type solid)) (layer "F.SilkS"))
    (fp_line (start -2.54 22.859) (end -2.54 -2.54)
      (stroke (width 0.15) (type solid)) (layer "F.SilkS"))
    (fp_line (start 22.859 -2.54) (end 22.859 22.859)
      (stroke (width 0.15) (type solid)) (layer "F.SilkS"))
    (fp_line (start 22.859 22.859) (end -2.54 22.859)
      (stroke (width 0.15) (type solid)) (layer "F.SilkS"))
    (fp_circle (center -2.921 0) (end -2.82 0)
      (stroke (width 0.15) (type solid)) (fill none) (layer "F.SilkS"))
    (fp_circle (center 0 -3.84) (end 0.05 -3.84)
      (stroke (width 0.15) (type solid)) (fill solid) (layer "F.SilkS"))
    (fp_circle (center 0 -3.84) (end 0.05 -3.84)
      (stroke (width 0.15) (type solid)) (fill solid) (layer "F.SilkS"))
    (fp_rect (start -2.667 -2.667) (end 22.987 22.987)
      (stroke (width 0.05) (type solid)) (fill none) (layer "F.CrtYd"))
    (fp_line (start -2.54 -2.54) (end 22.859 -2.54)
      (stroke (width 0.15) (type solid)) (layer "F.Fab"))
    (fp_line (start -2.54 22.859) (end -2.54 -2.54)
      (stroke (width 0.15) (type solid)) (layer "F.Fab"))
    (fp_line (start 22.859 -2.54) (end 22.859 22.859)
      (stroke (width 0.15) (type solid)) (layer "F.Fab"))
    (fp_line (start 22.859 22.859) (end -2.54 22.859)
      (stroke (width 0.15) (type solid)) (layer "F.Fab"))
    (fp_circle (center -2.921 0) (end -2.82 0)
      (stroke (width 0.15) (type solid)) (fill none) (layer "F.Fab"))
    (pad "1" thru_hole rect (at 0 0 90) (size 2.25 2.25) (drill 1.5) (layers "*.Cu" "*.Mask")
      (net 615 "/Ethernet/POE_ACTIVE") (pinfunction "CTRL") (pintype "input"))
    (pad "2" thru_hole circle (at 0 7.618 90) (size 2.25 2.25) (drill 1.5) (layers "*.Cu" "*.Mask")
      (net 604 "GNDD") (pinfunction "VIN-") (pintype "power_in"))
    (pad "3" thru_hole circle (at 0 12.698 90) (size 2.25 2.25) (drill 1.5) (layers "*.Cu" "*.Mask")
      (net 360 "/Ethernet/VDD") (pinfunction "VIN+") (pintype "power_in"))
    (pad "4" thru_hole circle (at 20.318 20.318 90) (size 2.25 2.25) (drill 1.5) (layers "*.Cu" "*.Mask")
      (net 864 "VIN_POE") (pinfunction "VOUT") (pintype "power_in"))
    (pad "5" thru_hole circle (at 20.318 10.159 90) (size 2.25 2.25) (drill 1.5) (layers "*.Cu" "*.Mask")
      (net 572 "unconnected-(PS1-TRIM-Pad5)") (pinfunction "TRIM") (pintype "passive+no_connect"))
    (pad "6" thru_hole circle (at 20.318 0 90) (size 2.25 2.25) (drill 1.5) (layers "*.Cu" "*.Mask")
      (net 9 "GND") (pinfunction "GND") (pintype "power_in"))
  )
	(footprint "data-center-rdimm-ddr4-tester-footprints:C_0402_1005Metric" (layer "F.Cu")
    (at 243.71 121.95)
    (descr "Capacitor SMD 0402")
    (tags "capacitor SMD 0402")
    (property "Author" "Antmicro")
    (property "Dielectric" "X5R")
    (property "License" "Apache-2.0")
    (property "MPN" "GRM155R61H104KE14D")
    (property "Manufacturer" "Murata")
    (property "Sheetfile" "pcie.kicad_sch")
    (property "Sheetname" "FPGA banks 115-116")
    (property "Val" "100n")
    (property "Voltage" "50V")
    (property "ki_description" " ")
    (attr smd)
    (fp_text reference "C318" (at -2.82 -1.475) (layer "F.SilkS")
        (effects (font (size 0.7 0.7) (thickness 0.15)) (justify left bottom))
    )
    (fp_text value "C_100n_0402" (at 0 1.4) (layer "F.Fab") hide
        (effects (font (size 0.7 0.7) (thickness 0.15)) (justify left bottom))
    )
    (fp_text user "Author: Antmicro" (at -0.932 4.17) (layer "F.Fab") hide
        (effects (font (size 0.7 0.7) (thickness 0.15)) (justify left bottom))
    )
    (fp_text user "License: Apache-2.0" (at -0.932 5.17) (layer "F.Fab") hide
        (effects (font (size 0.7 0.7) (thickness 0.15)) (justify left bottom))
    )
    (fp_text user "${REFERENCE}" (at -0.932 3.168) (layer "F.Fab") hide
        (effects (font (size 0.7 0.7) (thickness 0.15)) (justify left bottom))
    )
    (fp_rect (start -0.94 -0.47) (end 0.94 0.47)
      (stroke (width 0.05) (type solid)) (fill none) (layer "F.CrtYd"))
    (fp_rect (start -0.499 -0.249) (end 0.499 0.249)
      (stroke (width 0.15) (type solid)) (fill none) (layer "F.Fab"))
    (pad "1" smd roundrect (at -0.484 0) (size 0.59 0.64) (layers "F.Cu" "F.Paste" "F.Mask") (roundrect_rratio 0.25)
      (net 888 "/FPGA banks 115-116/GTR_REFCLK3_N") (pintype "passive"))
    (pad "2" smd roundrect (at 0.484 0) (size 0.59 0.64) (layers "F.Cu" "F.Paste" "F.Mask") (roundrect_rratio 0.25)
      (net 896 "GTR_REFCLK3_C_N") (pintype "passive"))
  )
)
